# S9S_MB_2U (Grand Teton) — schematic netlist excerpt (pin names and nets, part order shuffled) for the footprints in the layout excerpt that follows; sources: Cadence DE-HDL packaged netlist, KiCad conversion of 03242023_DA0F0TMBIJ0_F0T_Motherboard_J_brd_V01_OCP.brd

R1502  Q_RES  4.75K 1% CHIP  pkg 0402LF  page 208 : A = FM_CLK_CK440_SS_EN ; B = GND
C1152  Q_CAP  0.01UF 50V 10% X7R  pkg C0402  page 217 : A = VCC_PLD_CORE ; B = GND

(kicad_pcb
	(version 20260206)
	(generator "pcbnew")
	(generator_version "10.0")
	(general
		(thickness 1.6)
		(legacy_teardrops no)
	)
	(paper "A4")
	(title_block
		(title "03242023_DA0F0TMBIJ0_F0T_Motherboard_J_brd_V01_OCP.brd")
		(comment 1 "Grand Teton / footprints 4185-4186 of 6105")
	)
	(layers
		(0 "F.Cu" signal "TOP")
		(4 "In1.Cu" signal "GND")
		(6 "In2.Cu" signal "IN1")
		(8 "In3.Cu" signal "GND1")
		(10 "In4.Cu" signal "IN2")
		(12 "In5.Cu" signal "GND2")
		(14 "In6.Cu" signal "IN3")
		(16 "In7.Cu" signal "GND3")
		(18 "In8.Cu" signal "VCC")
		(20 "In9.Cu" signal "VCC1")
		(22 "In10.Cu" signal "GND4")
		(24 "In11.Cu" signal "IN4")
		(26 "In12.Cu" signal "GND5")
		(28 "In13.Cu" signal "IN5")
		(30 "In14.Cu" signal "GND6")
		(32 "In15.Cu" signal "IN6")
		(34 "In16.Cu" signal "GND7")
		(2 "B.Cu" signal "BOTTOM")
		(9 "F.Adhes" user "F.Adhesive")
		(11 "B.Adhes" user "B.Adhesive")
		(13 "F.Paste" user "Package Geometry/Pastemask Top")
		(15 "B.Paste" user "Package Geometry/Pastemask Bottom")
		(5 "F.SilkS" user "Ref Des/Silkscreen Top")
		(7 "B.SilkS" user "Ref Des/Silkscreen Bottom")
		(1 "F.Mask" user "Board Geometry/Soldermask Top")
		(3 "B.Mask" user "Board Geometry/Soldermask Bottom")
		(17 "Dwgs.User" user "User.Drawings")
		(19 "Cmts.User" user "User.Comments")
		(21 "Eco1.User" user "User.Eco1")
		(23 "Eco2.User" user "User.Eco2")
		(25 "Edge.Cuts" user "Board Geometry/Outline")
		(27 "Margin" user)
		(31 "F.CrtYd" user "Package Geometry/Place Bound Top")
		(29 "B.CrtYd" user "Package Geometry/Place Bound Bottom")
		(35 "F.Fab" user "Ref Des/Assembly Top")
		(33 "B.Fab" user "Ref Des/Assembly Bottom")
	)
	(footprint ""
		(layer "B.Cu")
		(at 180.155596 -112.175544 180)
		(property "Reference" "C1152"
			(at 0 0 0)
			(layer "B.SilkS")
			(hide yes)
			(effects
				(font
					(size 1.27 1.27)
				)
				(justify mirror)
			)
		)
		(property "Value" ""
			(at 0 0 0)
			(layer "B.Fab")
			(effects
				(font
					(size 1.27 1.27)
				)
				(justify mirror)
			)
		)
		(duplicate_pad_numbers_are_jumpers no)
		(fp_line
			(start 0.69215 0.2921)
			(end 0.69215 -0.2921)
			(stroke
				(width 0.1524)
				(type default)
			)
			(layer "B.SilkS")
		)
		(fp_line
			(start 0.69215 -0.2921)
			(end -0.69215 -0.2921)
			(stroke
				(width 0.1524)
				(type default)
			)
			(layer "B.SilkS")
		)
		(fp_line
			(start -0.69215 0.2921)
			(end 0.69215 0.2921)
			(stroke
				(width 0.1524)
				(type default)
			)
			(layer "B.SilkS")
		)
		(fp_line
			(start -0.69215 -0.2921)
			(end -0.69215 0.2921)
			(stroke
				(width 0.1524)
				(type default)
			)
			(layer "B.SilkS")
		)
		(fp_line
			(start 0.51435 0.2794)
			(end 0.51435 -0.2794)
			(stroke
				(width 0.1)
				(type default)
			)
			(layer "B.Fab")
		)
		(fp_line
			(start 0.51435 -0.2794)
			(end -0.51435 -0.2794)
			(stroke
				(width 0.1)
				(type default)
			)
			(layer "B.Fab")
		)
		(fp_line
			(start -0.51435 0.2794)
			(end 0.51435 0.2794)
			(stroke
				(width 0.1)
				(type default)
			)
			(layer "B.Fab")
		)
		(fp_line
			(start -0.51435 -0.2794)
			(end -0.51435 0.2794)
			(stroke
				(width 0.1)
				(type default)
			)
			(layer "B.Fab")
		)
		(pad "1" smd circle
			(at 0.40005 0)
			(size 0 0)
			(layers "B.Cu" "B.Mask" "B.Paste")
			(net "VCC_PLD_CORE")
		)
		(pad "2" smd circle
			(at -0.40005 0)
			(size 0 0)
			(layers "B.Cu" "B.Mask" "B.Paste")
			(net "GND")
		)
		(zone
			(layer "B.Cu")
			(hatch none 0.5)
			(connect_pads
				(clearance 0)
			)
			(min_thickness 0.25)
			(keepout
				(tracks not_allowed)
				(vias allowed)
				(pads allowed)
				(copperpour not_allowed)
				(footprints allowed)
			)
			(placement
				(enabled no)
				(sheetname "")
			)
			(fill
				(thermal_gap 0.5)
				(thermal_bridge_width 0.5)
				(island_removal_mode 0)
			)
			(polygon
				(pts
					(xy 179.965096 -112.263174) (xy 180.056536 -112.32134) (xy 180.255926 -112.32134) (xy 180.346096 -112.263174)
					(xy 180.346096 -112.087914) (xy 180.255926 -112.029494) (xy 180.056536 -112.029494) (xy 179.965096 -112.08766)
				)
			)
		)
	)
	(footprint ""
		(layer "B.Cu")
		(at 251.144786 -86.816946)
		(property "Reference" "R1502"
			(at 0 0 0)
			(layer "B.SilkS")
			(hide yes)
			(effects
				(font
					(size 1.27 1.27)
				)
				(justify mirror)
			)
		)
		(property "Value" ""
			(at 0 0 0)
			(layer "B.Fab")
			(effects
				(font
					(size 1.27 1.27)
				)
				(justify mirror)
			)
		)
		(duplicate_pad_numbers_are_jumpers no)
		(fp_line
			(start -0.7874 -0.4064)
			(end -0.7874 0.4064)
			(stroke
				(width 0.1524)
				(type default)
			)
			(layer "B.SilkS")
		)
		(fp_line
			(start -0.7874 0.4064)
			(end 0.7874 0.4064)
			(stroke
				(width 0.1524)
				(type default)
			)
			(layer "B.SilkS")
		)
		(fp_line
			(start 0.7874 -0.4064)
			(end -0.7874 -0.4064)
			(stroke
				(width 0.1524)
				(type default)
			)
			(layer "B.SilkS")
		)
		(fp_line
			(start 0.7874 0.4064)
			(end 0.7874 -0.4064)
			(stroke
				(width 0.1524)
				(type default)
			)
			(layer "B.SilkS")
		)
		(fp_line
			(start -0.67945 -0.3048)
			(end -0.67945 0.3048)
			(stroke
				(width 0.1)
				(type default)
			)
			(layer "B.Fab")
		)
		(fp_line
			(start -0.67945 0.3048)
			(end -0.120396 0.3048)
			(stroke
				(width 0.1)
				(type default)
			)
			(layer "B.Fab")
		)
		(fp_line
			(start -0.12065 -0.3048)
			(end -0.67945 -0.3048)
			(stroke
				(width 0.1)
				(type default)
			)
			(layer "B.Fab")
		)
		(fp_line
			(start -0.12065 -0.2794)
			(end -0.12065 -0.3048)
			(stroke
				(width 0.1)
				(type default)
			)
			(layer "B.Fab")
		)
		(fp_line
			(start -0.120396 0.2794)
			(end 0.12065 0.2794)
			(stroke
				(width 0.1)
				(type default)
			)
			(layer "B.Fab")
		)
		(fp_line
			(start -0.120396 0.3048)
			(end -0.120396 0.2794)
			(stroke
				(width 0.1)
				(type default)
			)
			(layer "B.Fab")
		)
		(fp_line
			(start 0.12065 -0.305054)
			(end 0.12065 -0.2794)
			(stroke
				(width 0.1)
				(type default)
			)
			(layer "B.Fab")
		)
		(fp_line
			(start 0.12065 -0.2794)
			(end -0.12065 -0.2794)
			(stroke
				(width 0.1)
				(type default)
			)
			(layer "B.Fab")
		)
		(fp_line
			(start 0.12065 0.2794)
			(end 0.12065 0.3048)
			(stroke
				(width 0.1)
				(type default)
			)
			(layer "B.Fab")
		)
		(fp_line
			(start 0.12065 0.3048)
			(end 0.67945 0.3048)
			(stroke
				(width 0.1)
				(type default)
			)
			(layer "B.Fab")
		)
		(fp_line
			(start 0.67945 -0.305054)
			(end 0.12065 -0.305054)
			(stroke
				(width 0.1)
				(type default)
			)
			(layer "B.Fab")
		)
		(fp_line
			(start 0.67945 0.3048)
			(end 0.67945 -0.305054)
			(stroke
				(width 0.1)
				(type default)
			)
			(layer "B.Fab")
		)
		(pad "1" smd circle
			(at 0.40005 0 180)
			(size 0 0)
			(layers "B.Cu" "B.Mask" "B.Paste")
			(net "FM_CLK_CK440_SS_EN")
		)
		(pad "2" smd circle
			(at -0.40005 0 180)
			(size 0 0)
			(layers "B.Cu" "B.Mask" "B.Paste")
			(net "GND")
		)
	)
)
